# BASEBOARD_FAB2 (Tioga Pass) — schematic netlist excerpt (pin names and nets, part order shuffled) for the footprints in the layout excerpt that follows; sources: Cadence DE-HDL packaged netlist, KiCad conversion of Wiwynn_Tioga_Pass_MB.brd

C1C8  CAP_A  0.1UF 16V 10% X7R  pkg 0402V  page 206 : A = VR_PVCCIN_CPU1_AVINSEN ; B = GND
C7B7  CAP  47UF 4V 20% X6S  pkg 0805  page 232 : A = PVPP_DEF ; B = GND
C3D23  CAP_A  22.0UF 4V 20% X6S  pkg 0603V  page 76 : A = PVCCIO_CPU1 ; B = GND

(kicad_pcb
	(version 20260206)
	(generator "pcbnew")
	(generator_version "10.0")
	(general
		(thickness 1.6)
		(legacy_teardrops no)
	)
	(paper "A4")
	(title_block
		(title "Wiwynn_Tioga_Pass_MB.brd")
		(comment 1 "Tioga Pass / footprints 1555-1557 of 4770")
	)
	(layers
		(0 "F.Cu" signal "TOP")
		(4 "In1.Cu" signal "L2GND")
		(6 "In2.Cu" signal "L3")
		(8 "In3.Cu" signal "L4GND")
		(10 "In4.Cu" signal "L5")
		(12 "In5.Cu" signal "L6GND")
		(14 "In6.Cu" signal "L7VCC")
		(16 "In7.Cu" signal "L8VCC")
		(18 "In8.Cu" signal "L9GND")
		(20 "In9.Cu" signal "L10")
		(22 "In10.Cu" signal "L11GND")
		(24 "In11.Cu" signal "L12")
		(26 "In12.Cu" signal "L13GND")
		(2 "B.Cu" signal "BOTTOM")
		(9 "F.Adhes" user "F.Adhesive")
		(11 "B.Adhes" user "B.Adhesive")
		(13 "F.Paste" user "Package Geometry/Pastemask Top")
		(15 "B.Paste" user "Package Geometry/Pastemask Bottom")
		(5 "F.SilkS" user "Ref Des/Silkscreen Top")
		(7 "B.SilkS" user "Ref Des/Silkscreen Bottom")
		(1 "F.Mask" user "Board Geometry/Soldermask Top")
		(3 "B.Mask" user "Board Geometry/Soldermask Bottom")
		(17 "Dwgs.User" user "User.Drawings")
		(19 "Cmts.User" user "User.Comments")
		(21 "Eco1.User" user "User.Eco1")
		(23 "Eco2.User" user "User.Eco2")
		(25 "Edge.Cuts" user "Board Geometry/Outline")
		(27 "Margin" user)
		(31 "F.CrtYd" user "Package Geometry/Place Bound Top")
		(29 "B.CrtYd" user "Package Geometry/Place Bound Bottom")
		(35 "F.Fab" user "Ref Des/Assembly Top")
		(33 "B.Fab" user "Ref Des/Assembly Bottom")
	)
	(footprint ""
		(layer "F.Cu")
		(at 333.849218 -129.921)
		(property "Reference" "C7B7"
			(at 0 0 0)
			(layer "F.SilkS")
			(hide yes)
			(effects
				(font
					(size 1.27 1.27)
				)
			)
		)
		(property "Value" ""
			(at 0 0 0)
			(layer "F.Fab")
			(effects
				(font
					(size 1.27 1.27)
				)
			)
		)
		(duplicate_pad_numbers_are_jumpers no)
		(fp_poly
			(pts
				(xy -0.7239 -0.2159) (xy 0.7239 -0.2159) (xy 0.7239 1.9939) (xy -0.7239 1.9939)
			)
			(stroke
				(width 0)
				(type default)
			)
			(fill no)
			(layer "F.CrtYd")
		)
		(fp_line
			(start -0.7239 -0.2159)
			(end -0.7239 1.9939)
			(stroke
				(width 0.1)
				(type default)
			)
			(layer "F.Fab")
		)
		(fp_line
			(start -0.7239 1.9939)
			(end 0.7239 1.9939)
			(stroke
				(width 0.1)
				(type default)
			)
			(layer "F.Fab")
		)
		(fp_line
			(start 0.7239 -0.2159)
			(end -0.7239 -0.2159)
			(stroke
				(width 0.1)
				(type default)
			)
			(layer "F.Fab")
		)
		(fp_line
			(start 0.7239 1.9939)
			(end 0.7239 -0.2159)
			(stroke
				(width 0.1)
				(type default)
			)
			(layer "F.Fab")
		)
		(pad "1" smd rect
			(at 0 0)
			(size 1.27 1.016)
			(layers "F.Cu" "F.Mask" "F.Paste")
			(net "PVPP_DEF")
		)
		(pad "2" smd rect
			(at 0 1.778)
			(size 1.27 1.016)
			(layers "F.Cu" "F.Mask" "F.Paste")
			(net "GND")
		)
		(zone
			(layer "F.Cu")
			(hatch none 0.5)
			(connect_pads
				(clearance 0)
			)
			(min_thickness 0.25)
			(keepout
				(tracks not_allowed)
				(vias allowed)
				(pads allowed)
				(copperpour not_allowed)
				(footprints allowed)
			)
			(placement
				(enabled no)
				(sheetname "")
			)
			(fill
				(thermal_gap 0.5)
				(thermal_bridge_width 0.5)
				(island_removal_mode 0)
			)
			(polygon
				(pts
					(xy 333.214218 -129.413) (xy 334.484218 -129.413) (xy 334.484218 -128.651) (xy 333.214218 -128.651)
				)
			)
		)
	)
	(footprint ""
		(layer "F.Cu")
		(at 18.288 -97.917 -90)
		(property "Reference" "C1C8"
			(at 0 0 270)
			(layer "F.SilkS")
			(hide yes)
			(effects
				(font
					(size 1.27 1.27)
				)
			)
		)
		(property "Value" ""
			(at 0 0 270)
			(layer "F.Fab")
			(effects
				(font
					(size 1.27 1.27)
				)
			)
		)
		(duplicate_pad_numbers_are_jumpers no)
		(fp_rect
			(start 0.3048 0.9906)
			(end -0.3048 -0.1016)
			(stroke
				(width 0)
				(type default)
			)
			(fill no)
			(layer "F.CrtYd")
		)
		(fp_line
			(start -0.3048 0.9906)
			(end 0.3048 0.9906)
			(stroke
				(width 0.1)
				(type default)
			)
			(layer "F.Fab")
		)
		(fp_line
			(start 0.3048 0.9906)
			(end 0.3048 -0.1016)
			(stroke
				(width 0.1)
				(type default)
			)
			(layer "F.Fab")
		)
		(fp_line
			(start -0.3048 -0.1016)
			(end -0.3048 0.9906)
			(stroke
				(width 0.1)
				(type default)
			)
			(layer "F.Fab")
		)
		(fp_line
			(start 0.3048 -0.1016)
			(end -0.3048 -0.1016)
			(stroke
				(width 0.1)
				(type default)
			)
			(layer "F.Fab")
		)
		(pad "1" smd rect
			(at 0 0 270)
			(size 0.508 0.508)
			(layers "F.Cu" "F.Mask" "F.Paste")
			(net "VR_PVCCIN_CPU1_AVINSEN")
		)
		(pad "2" smd rect
			(at 0 0.889 270)
			(size 0.508 0.508)
			(layers "F.Cu" "F.Mask" "F.Paste")
			(net "GND")
		)
		(zone
			(layer "F.Cu")
			(hatch none 0.5)
			(connect_pads
				(clearance 0)
			)
			(min_thickness 0.25)
			(keepout
				(tracks allowed)
				(vias not_allowed)
				(pads allowed)
				(copperpour not_allowed)
				(footprints allowed)
			)
			(placement
				(enabled no)
				(sheetname "")
			)
			(fill
				(thermal_gap 0.5)
				(thermal_bridge_width 0.5)
				(island_removal_mode 0)
			)
			(polygon
				(pts
					(xy 17.653 -97.663) (xy 18.034 -97.663) (xy 18.034 -98.171) (xy 17.653 -98.171)
				)
			)
		)
		(zone
			(layer "F.Cu")
			(hatch none 0.5)
			(connect_pads
				(clearance 0)
			)
			(min_thickness 0.25)
			(keepout
				(tracks not_allowed)
				(vias allowed)
				(pads allowed)
				(copperpour not_allowed)
				(footprints allowed)
			)
			(placement
				(enabled no)
				(sheetname "")
			)
			(fill
				(thermal_gap 0.5)
				(thermal_bridge_width 0.5)
				(island_removal_mode 0)
			)
			(polygon
				(pts
					(xy 17.653 -97.663) (xy 18.034 -97.663) (xy 18.034 -98.171) (xy 17.653 -98.171)
				)
			)
		)
	)
	(footprint ""
		(layer "F.Cu")
		(at 113.867692 -71.714614 180)
		(property "Reference" "C3D23"
			(at 0 0 180)
			(layer "F.SilkS")
			(hide yes)
			(effects
				(font
					(size 1.27 1.27)
				)
			)
		)
		(property "Value" ""
			(at 0 0 180)
			(layer "F.Fab")
			(effects
				(font
					(size 1.27 1.27)
				)
			)
		)
		(duplicate_pad_numbers_are_jumpers no)
		(fp_poly
			(pts
				(xy -0.4953 -0.2032) (xy 0.4953 -0.2032) (xy 0.4953 1.6002) (xy -0.4953 1.6002)
			)
			(stroke
				(width 0)
				(type default)
			)
			(fill no)
			(layer "F.CrtYd")
		)
		(fp_line
			(start 0.4953 1.6002)
			(end -0.4953 1.6002)
			(stroke
				(width 0.1)
				(type default)
			)
			(layer "F.Fab")
		)
		(fp_line
			(start 0.4953 -0.2032)
			(end 0.4953 1.6002)
			(stroke
				(width 0.1)
				(type default)
			)
			(layer "F.Fab")
		)
		(fp_line
			(start -0.4953 1.6002)
			(end -0.4953 -0.2032)
			(stroke
				(width 0.1)
				(type default)
			)
			(layer "F.Fab")
		)
		(fp_line
			(start -0.4953 -0.2032)
			(end 0.4953 -0.2032)
			(stroke
				(width 0.1)
				(type default)
			)
			(layer "F.Fab")
		)
		(pad "1" smd rect
			(at 0 0 180)
			(size 0.762 0.889)
			(layers "F.Cu" "F.Mask" "F.Paste")
			(net "PVCCIO_CPU1")
		)
		(pad "2" smd rect
			(at 0 1.397 180)
			(size 0.762 0.889)
			(layers "F.Cu" "F.Mask" "F.Paste")
			(net "GND")
		)
		(zone
			(layer "F.Cu")
			(hatch none 0.5)
			(connect_pads
				(clearance 0)
			)
			(min_thickness 0.25)
			(keepout
				(tracks not_allowed)
				(vias allowed)
				(pads allowed)
				(copperpour not_allowed)
				(footprints allowed)
			)
			(placement
				(enabled no)
				(sheetname "")
			)
			(fill
				(thermal_gap 0.5)
				(thermal_bridge_width 0.5)
				(island_removal_mode 0)
			)
			(polygon
				(pts
					(xy 114.248692 -72.159114) (xy 113.486692 -72.159114) (xy 113.486692 -72.667114) (xy 114.248692 -72.667114)
				)
			)
		)
	)
)
